# TIMECARD (Time Appliance Project (Time Card)) — schematic netlist excerpt (pin names and nets, part order shuffled) for the footprints in the layout excerpt that follows; sources: Cadence DE-HDL packaged netlist, KiCad conversion of R4006-B0001-02_R01.brd

C84  CAPACITOR  0.1UF 10V 10%  pkg SMC_0402R_H022  page 23 : \1\ = XP3R3V_FPGA ; \2\ = SG

(kicad_pcb
	(version 20260206)
	(generator "pcbnew")
	(generator_version "10.0")
	(general
		(thickness 1.6)
		(legacy_teardrops no)
	)
	(paper "A4")
	(title_block
		(title "timecard-production-celestica-r4006 — R4006-B0001-02_R01.brd")
		(comment 1 "Time Appliance Project (Time Card) / footprints 352-352 of 1113")
	)
	(layers
		(0 "F.Cu" signal "TOP")
		(4 "In1.Cu" signal "L02_GND1")
		(6 "In2.Cu" signal "L03_SIG1")
		(8 "In3.Cu" signal "L04_GND2")
		(10 "In4.Cu" signal "L05_VCC1")
		(12 "In5.Cu" signal "L06_VCC2")
		(14 "In6.Cu" signal "L07_GND3")
		(16 "In7.Cu" signal "L08_SIG2")
		(18 "In8.Cu" signal "L09_GND4")
		(2 "B.Cu" signal "BOTTOM")
		(9 "F.Adhes" user "F.Adhesive")
		(11 "B.Adhes" user "B.Adhesive")
		(13 "F.Paste" user "Package Geometry/Pastemask Top")
		(15 "B.Paste" user "Package Geometry/Pastemask Bottom")
		(5 "F.SilkS" user "Ref Des/Silkscreen Top")
		(7 "B.SilkS" user "Ref Des/Silkscreen Bottom")
		(1 "F.Mask" user "Board Geometry/Soldermask Top")
		(3 "B.Mask" user "Board Geometry/Soldermask Bottom")
		(17 "Dwgs.User" user "User.Drawings")
		(19 "Cmts.User" user "User.Comments")
		(21 "Eco1.User" user "User.Eco1")
		(23 "Eco2.User" user "User.Eco2")
		(25 "Edge.Cuts" user "Board Geometry/Outline")
		(27 "Margin" user)
		(31 "F.CrtYd" user "Package Geometry/Place Bound Top")
		(29 "B.CrtYd" user "Package Geometry/Place Bound Bottom")
		(35 "F.Fab" user "Ref Des/Assembly Top")
		(33 "B.Fab" user "Ref Des/Assembly Bottom")
	)
	(footprint ""
		(layer "F.Cu")
		(at 15.3924 -42.37863 -90)
		(property "Reference" "C84"
			(at 2.11963 -0.64135 90)
			(unlocked yes)
			(layer "F.SilkS")
			(effects
				(font
					(size 0.635 0.4064)
					(thickness 0.1524)
				)
			)
		)
		(property "Value" "VAL*"
			(at 0.0762 2.067306 270)
			(unlocked yes)
			(layer "F.Fab")
			(hide yes)
			(effects
				(font
					(size 0.7874 0.5842)
					(thickness 0.1524)
				)
			)
		)
		(property "Tolerance" "TOL*"
			(at 0.0762 3.032506 270)
			(unlocked yes)
			(layer "Cmts.User")
			(hide yes)
			(effects
				(font
					(size 0.7874 0.5842)
					(thickness 0.1524)
				)
			)
		)
		(property "User Part Number" "PARTNUM*"
			(at 0.1016 4.023106 270)
			(unlocked yes)
			(layer "Cmts.User")
			(hide yes)
			(effects
				(font
					(size 0.7874 0.5842)
					(thickness 0.1524)
				)
			)
		)
		(property "Device Type" "CAPACITOR-G105-0B104-CK,0.1UF,A"
			(at 0.0508 1.127506 270)
			(unlocked yes)
			(layer "F.Fab")
			(hide yes)
			(effects
				(font
					(size 0.7874 0.5842)
					(thickness 0.1524)
				)
			)
		)
		(duplicate_pad_numbers_are_jumpers no)
		(fp_line
			(start -1.143 0.5588)
			(end 1.143 0.5588)
			(stroke
				(width 0.1)
				(type default)
			)
			(layer "F.SilkS")
		)
		(fp_line
			(start 1.143 0.5588)
			(end 1.143 -0.5588)
			(stroke
				(width 0.1)
				(type default)
			)
			(layer "F.SilkS")
		)
		(fp_line
			(start -1.143 -0.5588)
			(end -1.143 0.5588)
			(stroke
				(width 0.1)
				(type default)
			)
			(layer "F.SilkS")
		)
		(fp_line
			(start 1.143 -0.5588)
			(end -1.143 -0.5588)
			(stroke
				(width 0.1)
				(type default)
			)
			(layer "F.SilkS")
		)
		(fp_rect
			(start 1.143 0.5588)
			(end -1.143 -0.5588)
			(stroke
				(width 0)
				(type default)
			)
			(fill no)
			(layer "F.CrtYd")
		)
		(fp_line
			(start -0.508 0.3048)
			(end 0.508 0.3048)
			(stroke
				(width 0.1)
				(type default)
			)
			(layer "F.Fab")
		)
		(fp_line
			(start 0.508 0.3048)
			(end 0.508 -0.3048)
			(stroke
				(width 0.1)
				(type default)
			)
			(layer "F.Fab")
		)
		(fp_line
			(start -0.508 -0.3048)
			(end -0.508 0.3048)
			(stroke
				(width 0.1)
				(type default)
			)
			(layer "F.Fab")
		)
		(fp_line
			(start 0.508 -0.3048)
			(end -0.508 -0.3048)
			(stroke
				(width 0.1)
				(type default)
			)
			(layer "F.Fab")
		)
		(pad "1" smd rect
			(at -0.5334 0 270)
			(size 0.7112 0.6096)
			(layers "F.Cu" "F.Mask" "F.Paste")
			(net "XP3R3V_FPGA")
		)
		(pad "2" smd rect
			(at 0.5334 0 270)
			(size 0.7112 0.6096)
			(layers "F.Cu" "F.Mask" "F.Paste")
			(net "SG")
		)
		(zone
			(layer "F.Cu")
			(hatch none 0.5)
			(connect_pads
				(clearance 0)
			)
			(min_thickness 0.25)
			(keepout
				(tracks allowed)
				(vias not_allowed)
				(pads allowed)
				(copperpour not_allowed)
				(footprints allowed)
			)
			(placement
				(enabled no)
				(sheetname "")
			)
			(fill
				(thermal_gap 0.5)
				(thermal_bridge_width 0.5)
				(island_removal_mode 0)
			)
			(polygon
				(pts
					(xy 15.0876 -42.30243) (xy 15.6972 -42.30243) (xy 15.6972 -42.45483) (xy 15.0876 -42.45483)
				)
			)
		)
	)
)
